# T6G (Grand Teton) — schematic netlist excerpt (pin names and nets, part order shuffled) for the footprints in the layout excerpt that follows; sources: Cadence DE-HDL packaged netlist, KiCad conversion of 04192023_DAF0TMB3IC0_F0TG_MB_C_brd_V02_OCP.brd

R1468  Q_RES  1K 1% CHIP  pkg 0201LF  page 185 : A = P1V8_CPU1_RT_1D ; B = SMB_RT_CPU1_P2_ROM_MUX_1D_SDA
R799  Q_RES  0 5% CHIP  pkg 0201LF  page 185 : A = SMB_RT_CPU0_P0_ROM_MUX_2D_R_SCL ; B = SMB_RT_CPU0_P0_ROM_MUX_2D_SCL
C6075  Q_CAP  0.001UF 50V 10% X7R  pkg C0402  page 177 : A = P1V2_AUX ; B = GND

(kicad_pcb
	(version 20260206)
	(generator "pcbnew")
	(generator_version "10.0")
	(general
		(thickness 1.6)
		(legacy_teardrops no)
	)
	(paper "A4")
	(title_block
		(title "04192023_DAF0TMB3IC0_F0TG_MB_C_brd_V02_OCP.brd")
		(comment 1 "Grand Teton / footprints 5533-5535 of 8354")
	)
	(layers
		(0 "F.Cu" signal "TOP")
		(4 "In1.Cu" signal "GND")
		(6 "In2.Cu" signal "IN1")
		(8 "In3.Cu" signal "GND1")
		(10 "In4.Cu" signal "IN2")
		(12 "In5.Cu" signal "GND2")
		(14 "In6.Cu" signal "IN3")
		(16 "In7.Cu" signal "GND3")
		(18 "In8.Cu" signal "VCC")
		(20 "In9.Cu" signal "VCC1")
		(22 "In10.Cu" signal "GND4")
		(24 "In11.Cu" signal "IN4")
		(26 "In12.Cu" signal "GND5")
		(28 "In13.Cu" signal "IN5")
		(30 "In14.Cu" signal "GND6")
		(32 "In15.Cu" signal "IN6")
		(34 "In16.Cu" signal "GND7")
		(2 "B.Cu" signal "BOTTOM")
		(9 "F.Adhes" user "F.Adhesive")
		(11 "B.Adhes" user "B.Adhesive")
		(13 "F.Paste" user "Package Geometry/Pastemask Top")
		(15 "B.Paste" user "Package Geometry/Pastemask Bottom")
		(5 "F.SilkS" user "Ref Des/Silkscreen Top")
		(7 "B.SilkS" user "Ref Des/Silkscreen Bottom")
		(1 "F.Mask" user "Board Geometry/Soldermask Top")
		(3 "B.Mask" user "Board Geometry/Soldermask Bottom")
		(17 "Dwgs.User" user "User.Drawings")
		(19 "Cmts.User" user "User.Comments")
		(21 "Eco1.User" user "User.Eco1")
		(23 "Eco2.User" user "User.Eco2")
		(25 "Edge.Cuts" user "Board Geometry/Outline")
		(27 "Margin" user)
		(31 "F.CrtYd" user "Package Geometry/Place Bound Top")
		(29 "B.CrtYd" user "Package Geometry/Place Bound Bottom")
		(35 "F.Fab" user "Ref Des/Assembly Top")
		(33 "B.Fab" user "Ref Des/Assembly Bottom")
	)
	(footprint ""
		(layer "B.Cu")
		(at 126.892304 -32.867092 -90)
		(property "Reference" "C6075"
			(at 0 0 90)
			(layer "B.SilkS")
			(hide yes)
			(effects
				(font
					(size 1.27 1.27)
				)
				(justify mirror)
			)
		)
		(property "Value" ""
			(at 0 0 90)
			(layer "B.Fab")
			(effects
				(font
					(size 1.27 1.27)
				)
				(justify mirror)
			)
		)
		(duplicate_pad_numbers_are_jumpers no)
		(fp_line
			(start -0.7874 0.4064)
			(end 0.7874 0.4064)
			(stroke
				(width 0.1524)
				(type default)
			)
			(layer "B.SilkS")
		)
		(fp_line
			(start 0.7874 0.4064)
			(end 0.7874 -0.4064)
			(stroke
				(width 0.1524)
				(type default)
			)
			(layer "B.SilkS")
		)
		(fp_line
			(start -0.7874 -0.4064)
			(end -0.7874 0.4064)
			(stroke
				(width 0.1524)
				(type default)
			)
			(layer "B.SilkS")
		)
		(fp_line
			(start 0.7874 -0.4064)
			(end -0.7874 -0.4064)
			(stroke
				(width 0.1524)
				(type default)
			)
			(layer "B.SilkS")
		)
		(fp_line
			(start -0.67945 0.3048)
			(end -0.120396 0.3048)
			(stroke
				(width 0.1)
				(type default)
			)
			(layer "B.Fab")
		)
		(fp_line
			(start -0.120396 0.3048)
			(end -0.120396 0.2794)
			(stroke
				(width 0.1)
				(type default)
			)
			(layer "B.Fab")
		)
		(fp_line
			(start 0.12065 0.3048)
			(end 0.67945 0.3048)
			(stroke
				(width 0.1)
				(type default)
			)
			(layer "B.Fab")
		)
		(fp_line
			(start 0.67945 0.3048)
			(end 0.67945 -0.305054)
			(stroke
				(width 0.1)
				(type default)
			)
			(layer "B.Fab")
		)
		(fp_line
			(start -0.120396 0.2794)
			(end 0.12065 0.2794)
			(stroke
				(width 0.1)
				(type default)
			)
			(layer "B.Fab")
		)
		(fp_line
			(start 0.12065 0.2794)
			(end 0.12065 0.3048)
			(stroke
				(width 0.1)
				(type default)
			)
			(layer "B.Fab")
		)
		(fp_line
			(start -0.12065 -0.2794)
			(end -0.12065 -0.3048)
			(stroke
				(width 0.1)
				(type default)
			)
			(layer "B.Fab")
		)
		(fp_line
			(start 0.12065 -0.2794)
			(end -0.12065 -0.2794)
			(stroke
				(width 0.1)
				(type default)
			)
			(layer "B.Fab")
		)
		(fp_line
			(start -0.67945 -0.3048)
			(end -0.67945 0.3048)
			(stroke
				(width 0.1)
				(type default)
			)
			(layer "B.Fab")
		)
		(fp_line
			(start -0.12065 -0.3048)
			(end -0.67945 -0.3048)
			(stroke
				(width 0.1)
				(type default)
			)
			(layer "B.Fab")
		)
		(fp_line
			(start 0.12065 -0.305054)
			(end 0.12065 -0.2794)
			(stroke
				(width 0.1)
				(type default)
			)
			(layer "B.Fab")
		)
		(fp_line
			(start 0.67945 -0.305054)
			(end 0.12065 -0.305054)
			(stroke
				(width 0.1)
				(type default)
			)
			(layer "B.Fab")
		)
		(pad "1" smd circle
			(at 0.40005 0 90)
			(size 0 0)
			(layers "B.Cu" "B.Mask" "B.Paste")
			(net "P1V2_AUX")
		)
		(pad "2" smd circle
			(at -0.40005 0 90)
			(size 0 0)
			(layers "B.Cu" "B.Mask" "B.Paste")
			(net "GND")
		)
	)
	(footprint ""
		(layer "B.Cu")
		(at 255.905 -340.76132 180)
		(property "Reference" "R799"
			(at 0 0 0)
			(layer "B.SilkS")
			(hide yes)
			(effects
				(font
					(size 1.27 1.27)
				)
				(justify mirror)
			)
		)
		(property "Value" ""
			(at 0 0 0)
			(layer "B.Fab")
			(effects
				(font
					(size 1.27 1.27)
				)
				(justify mirror)
			)
		)
		(duplicate_pad_numbers_are_jumpers no)
		(fp_line
			(start 0.32512 0.175006)
			(end 0.32512 -0.175006)
			(stroke
				(width 0.1)
				(type default)
			)
			(layer "B.Fab")
		)
		(fp_line
			(start 0.32512 -0.175006)
			(end -0.32512 -0.175006)
			(stroke
				(width 0.1)
				(type default)
			)
			(layer "B.Fab")
		)
		(fp_line
			(start -0.32512 0.175006)
			(end 0.32512 0.175006)
			(stroke
				(width 0.1)
				(type default)
			)
			(layer "B.Fab")
		)
		(fp_line
			(start -0.32512 -0.175006)
			(end -0.32512 0.175006)
			(stroke
				(width 0.1)
				(type default)
			)
			(layer "B.Fab")
		)
		(pad "1" smd rect
			(at 0.2667 0)
			(size 0.3048 0.381)
			(layers "B.Cu" "B.Mask" "B.Paste")
			(net "SMB_RT_CPU0_P0_ROM_MUX_2D_R_SCL")
		)
		(pad "2" smd rect
			(at -0.2667 0 180)
			(size 0.3048 0.381)
			(layers "B.Cu" "B.Mask" "B.Paste")
			(net "SMB_RT_CPU0_P0_ROM_MUX_2D_SCL")
		)
	)
	(footprint ""
		(layer "B.Cu")
		(at 157.226 -416.9664 180)
		(property "Reference" "R1468"
			(at 0 0 0)
			(layer "B.SilkS")
			(hide yes)
			(effects
				(font
					(size 1.27 1.27)
				)
				(justify mirror)
			)
		)
		(property "Value" ""
			(at 0 0 0)
			(layer "B.Fab")
			(effects
				(font
					(size 1.27 1.27)
				)
				(justify mirror)
			)
		)
		(duplicate_pad_numbers_are_jumpers no)
		(fp_line
			(start 0.32512 0.175006)
			(end 0.32512 -0.175006)
			(stroke
				(width 0.1)
				(type default)
			)
			(layer "B.Fab")
		)
		(fp_line
			(start 0.32512 -0.175006)
			(end -0.32512 -0.175006)
			(stroke
				(width 0.1)
				(type default)
			)
			(layer "B.Fab")
		)
		(fp_line
			(start -0.32512 0.175006)
			(end 0.32512 0.175006)
			(stroke
				(width 0.1)
				(type default)
			)
			(layer "B.Fab")
		)
		(fp_line
			(start -0.32512 -0.175006)
			(end -0.32512 0.175006)
			(stroke
				(width 0.1)
				(type default)
			)
			(layer "B.Fab")
		)
		(pad "1" smd rect
			(at 0.2667 0)
			(size 0.3048 0.381)
			(layers "B.Cu" "B.Mask" "B.Paste")
			(net "P1V8_CPU1_RT_1D")
		)
		(pad "2" smd rect
			(at -0.2667 0 180)
			(size 0.3048 0.381)
			(layers "B.Cu" "B.Mask" "B.Paste")
			(net "SMB_RT_CPU1_P2_ROM_MUX_1D_SDA")
		)
	)
)
